# BASEBOARD_FAB2 (Tioga Pass) — schematic netlist excerpt (pin names and nets, part order shuffled) for the footprints in the layout excerpt that follows; sources: Cadence DE-HDL packaged netlist, KiCad conversion of Wiwynn_Tioga_Pass_MB.brd

R3D1  RES  90.9 1% CHIP  pkg 0402  page 55 : A = A_CPU1_KLM_RCOMP0 ; B = GND
C4G1  CAP_A  0.01UF 25V 10% X7R  pkg 0402V  page 98 : A = M_B_CPU_VREF ; B = GND
C5A7  CAP_A  47UF 4V 20% X5R  pkg 0603V  page 220 : A = PVDDQ_DEF ; B = GND

(kicad_pcb
	(version 20260206)
	(generator "pcbnew")
	(generator_version "10.0")
	(general
		(thickness 1.6)
		(legacy_teardrops no)
	)
	(paper "A4")
	(title_block
		(title "Wiwynn_Tioga_Pass_MB.brd")
		(comment 1 "Tioga Pass / footprints 1997-1999 of 4770")
	)
	(layers
		(0 "F.Cu" signal "TOP")
		(4 "In1.Cu" signal "L2GND")
		(6 "In2.Cu" signal "L3")
		(8 "In3.Cu" signal "L4GND")
		(10 "In4.Cu" signal "L5")
		(12 "In5.Cu" signal "L6GND")
		(14 "In6.Cu" signal "L7VCC")
		(16 "In7.Cu" signal "L8VCC")
		(18 "In8.Cu" signal "L9GND")
		(20 "In9.Cu" signal "L10")
		(22 "In10.Cu" signal "L11GND")
		(24 "In11.Cu" signal "L12")
		(26 "In12.Cu" signal "L13GND")
		(2 "B.Cu" signal "BOTTOM")
		(9 "F.Adhes" user "F.Adhesive")
		(11 "B.Adhes" user "B.Adhesive")
		(13 "F.Paste" user "Package Geometry/Pastemask Top")
		(15 "B.Paste" user "Package Geometry/Pastemask Bottom")
		(5 "F.SilkS" user "Ref Des/Silkscreen Top")
		(7 "B.SilkS" user "Ref Des/Silkscreen Bottom")
		(1 "F.Mask" user "Board Geometry/Soldermask Top")
		(3 "B.Mask" user "Board Geometry/Soldermask Bottom")
		(17 "Dwgs.User" user "User.Drawings")
		(19 "Cmts.User" user "User.Comments")
		(21 "Eco1.User" user "User.Eco1")
		(23 "Eco2.User" user "User.Eco2")
		(25 "Edge.Cuts" user "Board Geometry/Outline")
		(27 "Margin" user)
		(31 "F.CrtYd" user "Package Geometry/Place Bound Top")
		(29 "B.CrtYd" user "Package Geometry/Place Bound Bottom")
		(35 "F.Fab" user "Ref Des/Assembly Top")
		(33 "B.Fab" user "Ref Des/Assembly Bottom")
	)
	(footprint ""
		(layer "F.Cu")
		(at 269.559532 -149.8092 90)
		(property "Reference" "C5A7"
			(at 1.848866 0.752348 90)
			(unlocked yes)
			(layer "F.SilkS")
			(effects
				(font
					(size 1.27 0.9652)
					(thickness 0.1524)
				)
			)
		)
		(property "Value" ""
			(at 0 0 90)
			(layer "F.Fab")
			(effects
				(font
					(size 1.27 1.27)
				)
			)
		)
		(duplicate_pad_numbers_are_jumpers no)
		(fp_rect
			(start -0.500126 1.598422)
			(end 0.500126 -0.201422)
			(stroke
				(width 0)
				(type default)
			)
			(fill no)
			(layer "F.CrtYd")
		)
		(fp_line
			(start 0.500126 -0.201422)
			(end 0.500126 1.598422)
			(stroke
				(width 0.1)
				(type default)
			)
			(layer "F.Fab")
		)
		(fp_line
			(start -0.500126 -0.201422)
			(end 0.500126 -0.201422)
			(stroke
				(width 0.1)
				(type default)
			)
			(layer "F.Fab")
		)
		(fp_line
			(start 0.500126 1.598422)
			(end -0.500126 1.598422)
			(stroke
				(width 0.1)
				(type default)
			)
			(layer "F.Fab")
		)
		(fp_line
			(start -0.500126 1.598422)
			(end -0.500126 -0.201422)
			(stroke
				(width 0.1)
				(type default)
			)
			(layer "F.Fab")
		)
		(pad "1" smd rect
			(at 0 0)
			(size 0.889 0.9906)
			(layers "F.Cu" "F.Mask" "F.Paste")
			(net "PVDDQ_DEF")
		)
		(pad "2" smd rect
			(at 0 1.397)
			(size 0.889 0.9906)
			(layers "F.Cu" "F.Mask" "F.Paste")
			(net "GND")
		)
		(zone
			(layer "F.Cu")
			(hatch none 0.5)
			(connect_pads
				(clearance 0)
			)
			(min_thickness 0.25)
			(keepout
				(tracks allowed)
				(vias not_allowed)
				(pads allowed)
				(copperpour not_allowed)
				(footprints allowed)
			)
			(placement
				(enabled no)
				(sheetname "")
			)
			(fill
				(thermal_gap 0.5)
				(thermal_bridge_width 0.5)
				(island_removal_mode 0)
			)
			(polygon
				(pts
					(xy 270.512032 -149.3139) (xy 270.512032 -150.3045) (xy 270.004032 -150.3045) (xy 270.004032 -149.3139)
				)
			)
		)
		(zone
			(layer "F.Cu")
			(hatch none 0.5)
			(connect_pads
				(clearance 0)
			)
			(min_thickness 0.25)
			(keepout
				(tracks not_allowed)
				(vias allowed)
				(pads allowed)
				(copperpour not_allowed)
				(footprints allowed)
			)
			(placement
				(enabled no)
				(sheetname "")
			)
			(fill
				(thermal_gap 0.5)
				(thermal_bridge_width 0.5)
				(island_removal_mode 0)
			)
			(polygon
				(pts
					(xy 270.512032 -149.3139) (xy 270.512032 -150.3045) (xy 270.004032 -150.3045) (xy 270.004032 -149.3139)
				)
			)
		)
	)
	(footprint ""
		(layer "F.Cu")
		(at 191.897 -13.3985)
		(property "Reference" "C4G1"
			(at 0 0 0)
			(layer "F.SilkS")
			(hide yes)
			(effects
				(font
					(size 1.27 1.27)
				)
			)
		)
		(property "Value" ""
			(at 0 0 0)
			(layer "F.Fab")
			(effects
				(font
					(size 1.27 1.27)
				)
			)
		)
		(duplicate_pad_numbers_are_jumpers no)
		(fp_poly
			(pts
				(xy 0.3048 -0.1016) (xy 0.3048 0.9906) (xy -0.3048 0.9906) (xy -0.3048 -0.1016)
			)
			(stroke
				(width 0)
				(type default)
			)
			(fill no)
			(layer "F.CrtYd")
		)
		(fp_line
			(start -0.3048 -0.1016)
			(end -0.3048 0.9906)
			(stroke
				(width 0.1)
				(type default)
			)
			(layer "F.Fab")
		)
		(fp_line
			(start -0.3048 0.9906)
			(end 0.3048 0.9906)
			(stroke
				(width 0.1)
				(type default)
			)
			(layer "F.Fab")
		)
		(fp_line
			(start 0.3048 -0.1016)
			(end -0.3048 -0.1016)
			(stroke
				(width 0.1)
				(type default)
			)
			(layer "F.Fab")
		)
		(fp_line
			(start 0.3048 0.9906)
			(end 0.3048 -0.1016)
			(stroke
				(width 0.1)
				(type default)
			)
			(layer "F.Fab")
		)
		(pad "1" smd rect
			(at 0 0)
			(size 0.508 0.508)
			(layers "F.Cu" "F.Mask" "F.Paste")
			(net "M_B_CPU_VREF")
		)
		(pad "2" smd rect
			(at 0 0.889)
			(size 0.508 0.508)
			(layers "F.Cu" "F.Mask" "F.Paste")
			(net "GND")
		)
		(zone
			(layer "F.Cu")
			(hatch none 0.5)
			(connect_pads
				(clearance 0)
			)
			(min_thickness 0.25)
			(keepout
				(tracks allowed)
				(vias not_allowed)
				(pads allowed)
				(copperpour not_allowed)
				(footprints allowed)
			)
			(placement
				(enabled no)
				(sheetname "")
			)
			(fill
				(thermal_gap 0.5)
				(thermal_bridge_width 0.5)
				(island_removal_mode 0)
			)
			(polygon
				(pts
					(xy 191.643 -13.1445) (xy 192.151 -13.1445) (xy 192.151 -12.7635) (xy 191.643 -12.7635)
				)
			)
		)
		(zone
			(layer "F.Cu")
			(hatch none 0.5)
			(connect_pads
				(clearance 0)
			)
			(min_thickness 0.25)
			(keepout
				(tracks not_allowed)
				(vias allowed)
				(pads allowed)
				(copperpour not_allowed)
				(footprints allowed)
			)
			(placement
				(enabled no)
				(sheetname "")
			)
			(fill
				(thermal_gap 0.5)
				(thermal_bridge_width 0.5)
				(island_removal_mode 0)
			)
			(polygon
				(pts
					(xy 191.643 -12.7635) (xy 192.151 -12.7635) (xy 192.151 -13.1445) (xy 191.643 -13.1445)
				)
			)
		)
	)
	(footprint ""
		(layer "F.Cu")
		(at 110.0074 -83.8962)
		(property "Reference" "R3D1"
			(at 0 0 0)
			(layer "F.SilkS")
			(hide yes)
			(effects
				(font
					(size 1.27 1.27)
				)
			)
		)
		(property "Value" ""
			(at 0 0 0)
			(layer "F.Fab")
			(effects
				(font
					(size 1.27 1.27)
				)
			)
		)
		(duplicate_pad_numbers_are_jumpers no)
		(fp_poly
			(pts
				(xy -0.2794 -0.1016) (xy 0.2794 -0.1016) (xy 0.2794 0.9906) (xy -0.2794 0.9906)
			)
			(stroke
				(width 0)
				(type default)
			)
			(fill no)
			(layer "F.CrtYd")
		)
		(fp_line
			(start -0.2794 -0.1016)
			(end -0.2794 0.9906)
			(stroke
				(width 0.1)
				(type default)
			)
			(layer "F.Fab")
		)
		(fp_line
			(start -0.2794 0.9906)
			(end 0.2794 0.9906)
			(stroke
				(width 0.1)
				(type default)
			)
			(layer "F.Fab")
		)
		(fp_line
			(start 0.2794 -0.1016)
			(end -0.2794 -0.1016)
			(stroke
				(width 0.1)
				(type default)
			)
			(layer "F.Fab")
		)
		(fp_line
			(start 0.2794 0.9906)
			(end 0.2794 -0.1016)
			(stroke
				(width 0.1)
				(type default)
			)
			(layer "F.Fab")
		)
		(pad "1" smd rect
			(at 0 0)
			(size 0.508 0.508)
			(layers "F.Cu" "F.Mask" "F.Paste")
			(net "A_CPU1_KLM_RCOMP0")
		)
		(pad "2" smd rect
			(at 0 0.889)
			(size 0.508 0.508)
			(layers "F.Cu" "F.Mask" "F.Paste")
			(net "GND")
		)
		(zone
			(layer "F.Cu")
			(hatch none 0.5)
			(connect_pads
				(clearance 0)
			)
			(min_thickness 0.25)
			(keepout
				(tracks allowed)
				(vias not_allowed)
				(pads allowed)
				(copperpour not_allowed)
				(footprints allowed)
			)
			(placement
				(enabled no)
				(sheetname "")
			)
			(fill
				(thermal_gap 0.5)
				(thermal_bridge_width 0.5)
				(island_removal_mode 0)
			)
			(polygon
				(pts
					(xy 109.7534 -83.6422) (xy 110.2614 -83.6422) (xy 110.2614 -83.2612) (xy 109.7534 -83.2612)
				)
			)
		)
		(zone
			(layer "F.Cu")
			(hatch none 0.5)
			(connect_pads
				(clearance 0)
			)
			(min_thickness 0.25)
			(keepout
				(tracks not_allowed)
				(vias allowed)
				(pads allowed)
				(copperpour not_allowed)
				(footprints allowed)
			)
			(placement
				(enabled no)
				(sheetname "")
			)
			(fill
				(thermal_gap 0.5)
				(thermal_bridge_width 0.5)
				(island_removal_mode 0)
			)
			(polygon
				(pts
					(xy 109.7534 -83.2612) (xy 110.2614 -83.2612) (xy 110.2614 -83.6422) (xy 109.7534 -83.6422)
				)
			)
		)
	)
)
